FILE_TYPE = CONNECTIVITY;
{Allegro Design Entry HDL 17.4-2019 S026 (4007227) 1/17/2022}
"PAGE_NUMBER" = 79;
0"NC";
1"SMB_CPU0_4_XLTR_SCL";
2"FM_OCP_V3_2_AUX_PWR_R_EN";
3"RST_SMB_SWITCH_N";
4"IRQ_SML1_PMBUS_ALERT_N";
5"P1V8_RETIMER_CPU1_R_EN";
6"FM_UARTSW_LSB_N";
7"OCP_V3_2_P3V3_PLD_R_PWRGD";
8"FM_SOL_UART_CH_SEL";
9"FM_LED_PWRGD_PVDD18_S5_P1";
10"SGPIO_SCM_CLK_<1>";
11"FM_OCP_V3_2_AUX_PWR_EN";
12"CLK_GEN2_GPU_FPGA_OE_R_N";
13"PWRGD_PVDDCR_SOC_P1";
14"FM_LED_PWRGD_PVDD11_S3_P1";
15"FM_LED_PWRGD_PVDDIO_P1";
16"RST_SRST_PLD_BMC_N";
17"FPGA_IO3V3_RSVD_1";
18"FM_LED_PWRGD_PVDDCR_CPU1_P1";
19"PWRGD_P5V";
20"FM_LED_PWRGD_PVDDCR_SOC_P1";
21"CLK_GEN2_BMC_RC_OE_N";
22"P1V8_RETIMER_CPU1_EN";
23"P1V8_RETIMER_CPU0_EN";
24"SMB_1_PLD_3V3AUX_SCL_R2";
25"SMB_2_PLD_3V3AUX_SCL_R1";
26"SMB_2_PLD_3V3AUX_SDA_R1";
27"SCM_SYS_PWROK_R";
28"P1V8_RETIMER_CPU0_R_EN";
29"SCM_SPARE_1";
30"SCM_ROT_CPU_RST_R_N";
31"RST_MB_STBY_N";
32"SGPIO_OCP_V3_2_LD_N";
33"SGPIO_OCP_V3_2_DATAIN";
34"SGPIO_OCP_V3_2_DATAOUT";
35"SCM_SPARE_0";
36"SGPIO_OCP_V3_2_CLK";
37"FM_UARTSW_MSB_N";
38"P12V_OCP_V3_2_PLD_PWRGD";
39"GPU_3V3IO_RSVD3_FFU_ISO"CDS_PHYS_NET_NAME"GPU_3V3IO_RSVD3_FFU_ISO";
40"PRSNT_CABLE_GPU_B3_ISO_N"CDS_PHYS_NET_NAME"GPU_3V3IO_RSVD2_FFU_ISO";
41"SCM_SYS_PWROK";
42"PVDDCR_SOC_P1_EN";
43"PVDDCR_CPU0_P0_EN";
44"SMB_BMC_SWB_EN";
45"HP_LVC3_OCP_V3_2_P12V_PWRGD_R";
46"HP_LVC3_OCP_V3_2_PRSNT2_PLD_N";
47"E1S_0_PERST1_CLKREQ_R_N";
48"SGPIO_OCP_SFF_CLK";
49"OCP_V3_2_MAIN_PWR_EN";
50"OCP_V3_1_P3V3_PLD_R_PWRGD";
51"P12V_OCP_SFF_EN";
52"FM_BOARD_BMC_SKU_ID1";
53"FM_BOARD_BMC_SKU_ID2";
54"FM_LED_ACTIVE_E1S_0";
55"SGPIO_SCM_CLK_<0>";
56"SGPIO_OCP_SFF_DATAOUT";
57"P3V3_OCP_SFF_EN_R";
58"P12V_OCP_SFF_EN_R";
59"P3V3_OCP_SFF_EN";
60"SGPIO_OCP_SFF_DATAIN";
61"SGPIO_OCP_SFF_LD_N";
62"IRQ_UV_DETECT_N";
63"SMB_CPU0_4_XLTR_SDA";
64"FM_BOARD_BMC_SKU_ID3";
65"SGPIO_SCM_DO_<0>";
66"IRQ_HSC_FAULT_BUF_N";
67"FM_UV_ADR_TRIGGER_N";
68"SGPIO_SCM_DI_<1>";
69"SGPIO_SCM_LD_<0>";
70"PCIE_M2_SSD0_PRSNT_N";
71"SGPIO_SCM_LD_<1>";
72"OC_ALERT_N";
73"SMB_CPU0_4_XLTR_R_SCL";
74"SMB_CPU0_4_XLTR_R_SDA";
75"FM_BOARD_BMC_SKU_ID4";
76"JTAG_SCM_TRST_R_N";
77"UV_ALERT_N";
78"SMB_1_PLD_3V3AUX_SDA_R2";
79"PRSNT_CABLE_GPU_B3_ISO_R_N"CDS_PHYS_NET_NAME"GPU_3V3IO_RSVD2_FFU_ISO_R";
80"FM_FAN_PWR_EN";
81"SCM_SYS_PWRBTN_N";
82"GPU_3V3IO_RSVD3_FFU_ISO_R"CDS_PHYS_NET_NAME"GPU_3V3IO_RSVD3_FFU_ISO_R";
83"SMB_2_PLD_3V3AUX_SCL_R2";
84"SMB_1_PLD_3V3AUX_SDA_R1";
85"SMB_1_PLD_3V3AUX_SCL_R1";
86"FM_I3C_CPU1_MUX0_R_SEL";
87"CLK_GEN2_GPU_FPGA_OE_N";
88"FM_SYS_THROTTLE_R_N"CDS_PHYS_NET_NAME"FM_SYS_THROTTLE_R_N";
89"FM_SYS_THROTTLE_N"CDS_PHYS_NET_NAME"FM_SYS_THROTTLE_N";
90"JTAG_SCM_TRST_N"CDS_PHYS_NET_NAME"JTAG_SCM_TRST_N";
91"FM_I3C_CPU1_MUX1_OE_N";
92"FM_I3C_CPU1_MUX0_OE_N";
93"SCM_JTAG_MUX_S1";
94"FM_I3C_CPU0_MUX0_SEL";
95"FM_I3C_CPU0_MUX1_OE_N";
96"SCM_JTAG_MUX_S0";
97"SGPIO_SCM_DI_R<1>";
98"FM_I3C_CPU0_MUX0_OE_R_N";
99"FM_I3C_CPU1_MUX1_OE_R_N";
100"FM_I3C_CPU0_MUX1_R_SEL";
101"FM_I3C_CPU0_MUX0_R_SEL";
102"SGPIO_SCM_DI_R<0>";
103"SGPIO_SCM_INTR_R_N";
104"FM_I3C_CPU1_MUX0_OE_R_N";
105"SCM_JTAG_MUX_R_S1";
106"SCM_JTAG_MUX_R_S0";
107"FM_I3C_CPU0_MUX0_OE_N";
108"SGPIO_SCM_INTR_N";
109"FM_I3C_CPU0_MUX1_OE_R_N";
110"FM_I3C_CPU1_MUX1_SEL";
111"SGPIO_SCM_DI_<0>";
112"CPLD_PROGRAMN";
113"JTAG_SCM_PLD_TCK";
114"VIRTUAL_RESEAT";
115"CPLD_JTAG_EN";
116"JTAG_SCM_PLD_TMS";
117"JTAG_SCM_PLD_TDO";
118"JTAG_SCM_PLD_TDI";
119"E1S_0_PRSNT_N";
120"E1S_0_PERST1_CLKREQ_N";
121"FM_I3C_CPU0_MUX1_SEL";
122"FM_I3C_CPU1_MUX0_SEL";
123"VIRTUAL_RESEAT_FPGA_R_N";
124"VIRTUAL_RESEAT_FPGA_N";
125"SMB_2_PLD_3V3AUX_SDA_R2";
126"PRSNT_OCP_V3_2_N";
127"RST_SRST_PLD_BMC_R_N";
128"CLK_GEN2_BMC_RC_OE_R_N";
129"PWRGD_P5V_R2";
130"SGPIO_SCM_RESET_N";
131"SGPIO_SCM_DO_<1>";
132"PWRGD_PS_PWROK_PLD_ISO_R";
133"FM_I3C_CPU1_MUX1_R_SEL";
134"FM_BOARD_BMC_SKU_ID0";
135"FM_UV_ADR_TRIGGER_R_N";
136"IRQ_HSC_FAULT_BUF_R_N";
137"HSC_D_OC";
138"FM_OCP_V3_2_PWR_GOOD";
%"Q_RES"
"1","(-6825,4000)","2","pure_quanta","I112";
;
LOCATION"R6095"
$SEC"1"
CDS_SEC"1"
VALUE"0"
MATERIAL"CHIP"
PACK_TYPE"0402LF"
TOLERANCE"5%"
WATTAGE"1/16W"
CDS_LIB"pure_quanta"
BOM_COST"MEM"
PART_NUMBER"CS00002JB13";
"B"
$PN"2"66;
"A"
$PN"1"136;
%"Q_RES"
"1","(-6825,3950)","2","pure_quanta","I115";
;
LOCATION"R6096"
$SEC"1"
CDS_SEC"1"
VALUE"0"
MATERIAL"CHIP"
BOM_COST"MEM"
CDS_LIB"pure_quanta"
WATTAGE"1/16W"
TOLERANCE"5%"
PACK_TYPE"0402LF"
PART_NUMBER"CS00002JB13";
"B"
$PN"2"67;
"A"
$PN"1"135;
%"Q_RES"
"1","(-2775,4850)","0","pure_quanta","I121";
;
LOCATION"R4145"
$SEC"1"
CDS_SEC"1"
VALUE"33.2"
MATERIAL"CHIP"
TOLERANCE"1%"
WATTAGE"1/16W"
PACK_TYPE"0402LF"
CDS_LIB"pure_quanta"
PART_NUMBER"CS03322FB03";
"B"
$PN"2"40;
"A"
$PN"1"79;
%"Q_RES"
"1","(-2775,4800)","0","pure_quanta","I122";
;
LOCATION"R4146"
$SEC"1"
CDS_SEC"1"
VALUE"33.2"
TOLERANCE"1%"
MATERIAL"CHIP"
WATTAGE"1/16W"
PACK_TYPE"0402LF"
CDS_LIB"pure_quanta"
PART_NUMBER"CS03322FB03";
"B"
$PN"2"39;
"A"
$PN"1"82;
%"Q_RES"
"1","(-8450,4300)","2","pure_quanta","I128";
;
LOCATION"R6094"
$SEC"1"
CDS_SEC"1"
VALUE"0"
MATERIAL"EMPTY"
PACK_TYPE"0402LF"
TOLERANCE"5%"
WATTAGE"1/16W"
CDS_LIB"pure_quanta"
BOM_COST"MEM"
PART_NUMBER"CS00002JB13";
"B"
$PN"2"120;
"A"
$PN"1"47;
%"Q_RES"
"1","(-8450,4150)","2","pure_quanta","I129";
;
LOCATION"R6116"
$SEC"1"
CDS_SEC"1"
MATERIAL"CHIP"
VALUE"0"
PACK_TYPE"0402LF"
TOLERANCE"5%"
WATTAGE"1/16W"
CDS_LIB"pure_quanta"
BOM_COST"MEM"
PART_NUMBER"CS00002JB13";
"B"
$PN"2"119;
"A"
$PN"1"47;
%"Q_RES"
"1","(-2775,3950)","2","pure_quanta","I131";
;
LOCATION"R6117"
$SEC"1"
CDS_SEC"1"
VALUE"100"
TOLERANCE"1%"
PACK_TYPE"0402LF"
MATERIAL"CHIP"
WATTAGE"1/16W"
BOM_COST"MEM"
CDS_LIB"pure_quanta"
PART_NUMBER"CS11002FB07";
"B"
$PN"2"126;
"A"
$PN"1"46;
%"Q_RES"
"1","(-2775,4750)","2","pure_quanta","I139";
;
LOCATION"R407"
$SEC"1"
CDS_SEC"1"
VALUE"0"
BOM_COST"MEM"
WATTAGE"1/16W"
MATERIAL"CHIP"
TOLERANCE"5%"
PACK_TYPE"0402LF"
CDS_LIB"pure_quanta"
PART_NUMBER"CS00002JB13";
"B"
$PN"2"45;
"A"
$PN"1"38;
%"Q_RES"
"1","(-2775,3800)","2","pure_quanta","I141";
;
LOCATION"R419"
$SEC"1"
CDS_SEC"1"
VALUE"0"
PACK_TYPE"0402LF"
TOLERANCE"5%"
MATERIAL"CHIP"
WATTAGE"1/16W"
BOM_COST"MEM"
CDS_LIB"pure_quanta"
PART_NUMBER"CS00002JB13";
"B"
$PN"2"127;
"A"
$PN"1"16;
%"Q_RES"
"1","(-2775,3900)","0","pure_quanta","I144";
;
LOCATION"R439"
SEC"1"
VALUE"0"
MATERIAL"CHIP"
WATTAGE"1/16W"
TOLERANCE"5%"
PACK_TYPE"0402LF"
SEC_TYPE"0402LF"
CDS_LIB"pure_quanta"
PART_NUMBER"CS00002JB13";
"B"
$PN"2"129;
"A"
$PN"1"19;
%"Q_RES"
"1","(-2775,4050)","2","pure_quanta","I146";
;
LOCATION"R6850"
$SEC"1"
CDS_SEC"1"
VALUE"33"
CDS_LIB"pure_quanta"
BOM_COST"MEM"
WATTAGE"1/16W"
MATERIAL"CHIP"
TOLERANCE"5%"
PACK_TYPE"0402LF"
PART_NUMBER"CS03302JB10";
"B"
$PN"2"28;
"A"
$PN"1"23;
%"Q_RES"
"1","(-2775,3000)","2","pure_quanta","I147";
;
LOCATION"R6851"
$SEC"1"
CDS_SEC"1"
VALUE"33"
BOM_COST"MEM"
WATTAGE"1/16W"
MATERIAL"CHIP"
TOLERANCE"5%"
PACK_TYPE"0402LF"
CDS_LIB"pure_quanta"
PART_NUMBER"CS03302JB10";
"B"
$PN"2"5;
"A"
$PN"1"22;
%"Q_RES"
"1","(-6850,3300)","2","pure_quanta","I153";
;
LOCATION"R152"
$SEC"1"
CDS_SEC"1"
VALUE"33"
PACK_TYPE"0402LF"
TOLERANCE"5%"
MATERIAL"CHIP"
WATTAGE"1/16W"
BOM_COST"MEM"
CDS_LIB"pure_quanta"
PART_NUMBER"CS03302JB10";
"B"
$PN"2"58;
"A"
$PN"1"51;
%"Q_RES"
"1","(-2675,3400)","2","pure_quanta","I155";
;
LOCATION"R1179"
$SEC"1"
CDS_SEC"1"
VALUE"0"
BOM_COST"MEM"
WATTAGE"1/16W"
MATERIAL"CHIP"
TOLERANCE"5%"
PACK_TYPE"0402LF"
CDS_LIB"pure_quanta"
PART_NUMBER"CS00002JB13";
"B"
$PN"2"11;
"A"
$PN"1"2;
%"Q_RES"
"1","(-6850,2700)","2","pure_quanta","I16";
;
LOCATION"R160"
$SEC"1"
CDS_SEC"1"
VALUE"33"
PACK_TYPE"0402LF"
TOLERANCE"5%"
MATERIAL"CHIP"
WATTAGE"1/16W"
BOM_COST"MEM"
CDS_LIB"pure_quanta"
PART_NUMBER"CS03302JB10";
"B"
$PN"2"90;
"A"
$PN"1"76;
%"Q_RES"
"1","(-6850,2750)","2","pure_quanta","I17";
;
LOCATION"R992"
$SEC"1"
CDS_SEC"1"
VALUE"33"
PACK_TYPE"0402LF"
TOLERANCE"5%"
MATERIAL"CHIP"
WATTAGE"1/16W"
CDS_LIB"pure_quanta"
BOM_COST"MEM"
PART_NUMBER"CS03302JB10";
"B"
$PN"2"89;
"A"
$PN"1"88;
%"Q_RES"
"1","(-6850,2950)","2","pure_quanta","I18";
;
LOCATION"R493"
$SEC"1"
CDS_SEC"1"
VALUE"0"
PACK_TYPE"0402LF"
TOLERANCE"5%"
MATERIAL"CHIP"
WATTAGE"1/16W"
BOM_COST"MEM"
CDS_LIB"pure_quanta"
PART_NUMBER"CS00002JB13";
"B"
$PN"2"63;
"A"
$PN"1"74;
%"Q_RES"
"1","(-6850,3000)","2","pure_quanta","I19";
;
LOCATION"R70"
$SEC"1"
CDS_SEC"1"
VALUE"0"
PACK_TYPE"0402LF"
TOLERANCE"5%"
MATERIAL"CHIP"
WATTAGE"1/16W"
CDS_LIB"pure_quanta"
BOM_COST"MEM"
PART_NUMBER"CS00002JB13";
"B"
$PN"2"1;
"A"
$PN"1"73;
%"Q_RES"
"1","(-6850,3050)","2","pure_quanta","I20";
;
LOCATION"R6039"
$SEC"1"
CDS_SEC"1"
VALUE"0"
PACK_TYPE"0402LF"
TOLERANCE"5%"
MATERIAL"CHIP"
WATTAGE"1/16W"
CDS_LIB"pure_quanta"
BOM_COST"MEM"
PART_NUMBER"CS00002JB13";
"B"
$PN"2"137;
"A"
$PN"1"72;
%"Q_RES"
"1","(-6850,3100)","2","pure_quanta","I21";
;
LOCATION"R6038"
$SEC"1"
CDS_SEC"1"
VALUE"0"
BOM_COST"MEM"
CDS_LIB"pure_quanta"
WATTAGE"1/16W"
MATERIAL"CHIP"
TOLERANCE"5%"
PACK_TYPE"0402LF"
PART_NUMBER"CS00002JB13";
"B"
$PN"2"62;
"A"
$PN"1"77;
%"Q_RES"
"1","(-6850,3400)","2","pure_quanta","I23";
;
LOCATION"R23"
$SEC"1"
CDS_SEC"1"
VALUE"33"
CDS_LIB"pure_quanta"
PACK_TYPE"0402LF"
TOLERANCE"5%"
MATERIAL"CHIP"
WATTAGE"1/16W"
BOM_COST"MEM"
PART_NUMBER"CS03302JB10";
"B"
$PN"2"57;
"A"
$PN"1"59;
%"Q_RES"
"1","(-6825,3900)","2","pure_quanta","I24";
;
LOCATION"R168"
$SEC"1"
CDS_SEC"1"
VALUE"0"
BOM_COST"MEM"
CDS_LIB"pure_quanta"
WATTAGE"1/16W"
MATERIAL"CHIP"
TOLERANCE"5%"
PACK_TYPE"0402LF"
PART_NUMBER"CS00002JB13";
"B"
$PN"2"68;
"A"
$PN"1"97;
%"LCMXO3LF9400C5BG484C"
"4","(-5375,1250)","0","pure_quanta","I25";
;
LOCATION"U18"
$SEC"4"
CDS_SEC"4"
PART_TYPE"SMLF"
MATERIAL"IC"
VALUE"LCMXO3LF-9400C-5BG484C"
CDS_LIB"pure_quanta"
NEEDS_NO_SIZE"TRUE"
CDS_LMAN_SYM_OUTLINE"-400,250,400,-250"
PART_NUMBER"AJ094000T08";
"PT31C||JTAGENB"
$PN"E14"115;
"PT44D||DONE"
$PN"E17"123;
"PT44C||INITN"
$PN"F16"114;
"PT31D||PROGRAMN"
$PN"E15"112;
"PT22D||TMS"
$PN"C10"116;
"PT22C||TCK"
$PN"D10"113;
"PT15D||TDI"
$PN"E9"117;
"PT15C||TDO"
$PN"E8"118;
%"Q_RES"
"1","(-6850,4300)","2","pure_quanta","I43";
;
LOCATION"R172"
$SEC"1"
CDS_SEC"1"
VALUE"33"
CDS_LIB"pure_quanta"
BOM_COST"MEM"
WATTAGE"1/16W"
MATERIAL"CHIP"
TOLERANCE"5%"
PACK_TYPE"0402LF"
PART_NUMBER"CS03302JB10";
"B"
$PN"2"110;
"A"
$PN"1"133;
%"Q_RES"
"1","(-6850,4450)","2","pure_quanta","I44";
;
LOCATION"R58"
$SEC"1"
CDS_SEC"1"
VALUE"33"
PACK_TYPE"0402LF"
TOLERANCE"5%"
MATERIAL"CHIP"
WATTAGE"1/16W"
CDS_LIB"pure_quanta"
BOM_COST"MEM"
PART_NUMBER"CS03302JB10";
"B"
$PN"2"108;
"A"
$PN"1"103;
%"Q_RES"
"1","(-6850,4550)","2","pure_quanta","I45";
;
LOCATION"R167"
$SEC"1"
CDS_SEC"1"
VALUE"0"
BOM_COST"MEM"
CDS_LIB"pure_quanta"
WATTAGE"1/16W"
MATERIAL"CHIP"
TOLERANCE"5%"
PACK_TYPE"0402LF"
PART_NUMBER"CS00002JB13";
"B"
$PN"2"111;
"A"
$PN"1"102;
%"Q_RES"
"1","(-6850,4600)","2","pure_quanta","I46";
;
LOCATION"R49"
$SEC"1"
CDS_SEC"1"
VALUE"33"
CDS_LIB"pure_quanta"
BOM_COST"MEM"
WATTAGE"1/16W"
MATERIAL"CHIP"
TOLERANCE"5%"
PACK_TYPE"0402LF"
PART_NUMBER"CS03302JB10";
"B"
$PN"2"96;
"A"
$PN"1"106;
%"Q_RES"
"1","(-6850,4650)","2","pure_quanta","I47";
;
LOCATION"R165"
$SEC"1"
CDS_SEC"1"
VALUE"33"
PACK_TYPE"0402LF"
TOLERANCE"5%"
MATERIAL"CHIP"
WATTAGE"1/16W"
CDS_LIB"pure_quanta"
BOM_COST"MEM"
PART_NUMBER"CS03302JB10";
"B"
$PN"2"95;
"A"
$PN"1"109;
%"Q_RES"
"1","(-6850,4800)","2","pure_quanta","I48";
;
LOCATION"R169"
$SEC"1"
CDS_SEC"1"
VALUE"33"
PACK_TYPE"0402LF"
TOLERANCE"5%"
MATERIAL"CHIP"
WATTAGE"1/16W"
BOM_COST"MEM"
CDS_LIB"pure_quanta"
PART_NUMBER"CS03302JB10";
"B"
$PN"2"92;
"A"
$PN"1"104;
%"Q_RES"
"1","(-6850,4750)","2","pure_quanta","I49";
;
LOCATION"R50"
$SEC"1"
CDS_SEC"1"
VALUE"33"
PACK_TYPE"0402LF"
TOLERANCE"5%"
MATERIAL"CHIP"
WATTAGE"1/16W"
CDS_LIB"pure_quanta"
BOM_COST"MEM"
PART_NUMBER"CS03302JB10";
"B"
$PN"2"93;
"A"
$PN"1"105;
%"Q_RES"
"1","(-6850,4700)","2","pure_quanta","I50";
;
LOCATION"R164"
$SEC"1"
CDS_SEC"1"
VALUE"33"
PACK_TYPE"0402LF"
TOLERANCE"5%"
MATERIAL"CHIP"
WATTAGE"1/16W"
BOM_COST"MEM"
CDS_LIB"pure_quanta"
PART_NUMBER"CS03302JB10";
"B"
$PN"2"94;
"A"
$PN"1"101;
%"Q_RES"
"1","(-6850,4850)","2","pure_quanta","I51";
;
LOCATION"R166"
$SEC"1"
CDS_SEC"1"
VALUE"33"
PACK_TYPE"0402LF"
TOLERANCE"5%"
MATERIAL"CHIP"
WATTAGE"1/16W"
CDS_LIB"pure_quanta"
BOM_COST"MEM"
PART_NUMBER"CS03302JB10";
"B"
$PN"2"121;
"A"
$PN"1"100;
%"Q_RES"
"1","(-6850,4900)","2","pure_quanta","I52";
;
LOCATION"R171"
$SEC"1"
CDS_SEC"1"
VALUE"33"
PACK_TYPE"0402LF"
TOLERANCE"5%"
MATERIAL"CHIP"
WATTAGE"1/16W"
BOM_COST"MEM"
CDS_LIB"pure_quanta"
PART_NUMBER"CS03302JB10";
"B"
$PN"2"91;
"A"
$PN"1"99;
%"Q_RES"
"1","(-6850,4950)","2","pure_quanta","I53";
;
LOCATION"R170"
$SEC"1"
CDS_SEC"1"
VALUE"33"
PACK_TYPE"0402LF"
TOLERANCE"5%"
MATERIAL"CHIP"
WATTAGE"1/16W"
BOM_COST"MEM"
CDS_LIB"pure_quanta"
PART_NUMBER"CS03302JB10";
"B"
$PN"2"122;
"A"
$PN"1"86;
%"Q_RES"
"1","(-6850,5000)","2","pure_quanta","I54";
;
LOCATION"R163"
$SEC"1"
CDS_SEC"1"
VALUE"33"
PACK_TYPE"0402LF"
TOLERANCE"5%"
MATERIAL"CHIP"
WATTAGE"1/16W"
CDS_LIB"pure_quanta"
BOM_COST"MEM"
PART_NUMBER"CS03302JB10";
"B"
$PN"2"107;
"A"
$PN"1"98;
%"Q_RES"
"1","(-3825,1100)","2","pure_quanta","I55";
;
LOCATION"R6031"
$SEC"1"
CDS_SEC"1"
VALUE"33"
BOM_COST"MEM"
WATTAGE"1/16W"
MATERIAL"CHIP"
TOLERANCE"5%"
PACK_TYPE"0402LF"
CDS_LIB"pure_quanta"
PART_NUMBER"CS03302JB10";
"B"
$PN"2"123;
"A"
$PN"1"124;
%"Q_RES"
"1","(-2775,2850)","2","pure_quanta","I64";
;
LOCATION"R6030"
$SEC"1"
CDS_SEC"1"
VALUE"33"
CDS_LIB"pure_quanta"
PACK_TYPE"0402LF"
TOLERANCE"5%"
MATERIAL"CHIP"
WATTAGE"1/16W"
BOM_COST"MEM"
PART_NUMBER"CS03302JB10";
"B"
$PN"2"12;
"A"
$PN"1"87;
%"Q_RES"
"1","(-2775,2900)","2","pure_quanta","I65";
;
LOCATION"R6029"
$SEC"1"
CDS_SEC"1"
VALUE"33"
CDS_LIB"pure_quanta"
BOM_COST"MEM"
WATTAGE"1/16W"
MATERIAL"CHIP"
TOLERANCE"5%"
PACK_TYPE"0402LF"
PART_NUMBER"CS03302JB10";
"B"
$PN"2"128;
"A"
$PN"1"21;
%"Q_RES"
"1","(-2775,4100)","2","pure_quanta","I79";
;
LOCATION"R63"
$SEC"1"
CDS_SEC"1"
VALUE"33"
PACK_TYPE"0402LF"
TOLERANCE"5%"
MATERIAL"CHIP"
WATTAGE"1/16W"
CDS_LIB"pure_quanta"
BOM_COST"MEM"
PART_NUMBER"CS03302JB10";
"B"
$PN"2"41;
"A"
$PN"1"27;
%"Q_RES"
"1","(-2775,4600)","2","pure_quanta","I80";
;
LOCATION"R211"
$SEC"1"
CDS_SEC"1"
VALUE"0"
BOM_COST"MEM"
CDS_LIB"pure_quanta"
WATTAGE"1/16W"
MATERIAL"CHIP"
TOLERANCE"5%"
PACK_TYPE"0402LF"
PART_NUMBER"CS00002JB13";
"B"
$PN"2"125;
"A"
$PN"1"26;
%"Q_RES"
"1","(-2775,4650)","2","pure_quanta","I81";
;
LOCATION"R210"
$SEC"1"
CDS_SEC"1"
VALUE"0"
PACK_TYPE"0402LF"
TOLERANCE"5%"
MATERIAL"CHIP"
WATTAGE"1/16W"
CDS_LIB"pure_quanta"
BOM_COST"MEM"
PART_NUMBER"CS00002JB13";
"B"
$PN"2"83;
"A"
$PN"1"25;
%"Q_RES"
"1","(-2775,4900)","2","pure_quanta","I82";
;
LOCATION"R56"
$SEC"1"
CDS_SEC"1"
VALUE"0"
CDS_LIB"pure_quanta"
BOM_COST"MEM"
WATTAGE"1/16W"
MATERIAL"CHIP"
TOLERANCE"5%"
PACK_TYPE"0402LF"
PART_NUMBER"CS00002JB13";
"B"
$PN"2"78;
"A"
$PN"1"84;
%"Q_RES"
"1","(-2775,4950)","2","pure_quanta","I83";
;
LOCATION"R51"
$SEC"1"
CDS_SEC"1"
VALUE"0"
PACK_TYPE"0402LF"
TOLERANCE"5%"
MATERIAL"CHIP"
WATTAGE"1/16W"
BOM_COST"MEM"
CDS_LIB"pure_quanta"
PART_NUMBER"CS00002JB13";
"B"
$PN"2"24;
"A"
$PN"1"85;
%"LCMXO3LF9400C5BG484C"
"3","(-4825,3850)","0","pure_quanta","I94";
;
LOCATION"U18"
$SEC"3"
CDS_SEC"3"
PART_TYPE"SMLF"
VALUE"LCMXO3LF-9400C-5BG484C"
MATERIAL"IC"
CDS_LMAN_SYM_OUTLINE"-900,1250,900,-1250"
NEEDS_NO_SIZE"TRUE"
CDS_LIB"pure_quanta"
PART_NUMBER"AJ094000T08";
"PT43D"
$PN"C20"12;
"PT43C"
$PN"C19"128;
"PT42D"
$PN"G15"6;
"PT42C"
$PN"F15"7;
"PT42B"
$PN"B20"8;
"PT42A"
$PN"A19"9;
"PT41D"
$PN"D18"10;
"PT41C"
$PN"C18"11;
"PT40D"
$PN"D17"3;
"PT40C"
$PN"E16"18;
"PT40B"
$PN"B18"20;
"PT40A"
$PN"A17"13;
"PT39D"
$PN"D16"17;
"PT39C"
$PN"C17"127;
"PT39B"
$PN"B17"43;
"PT39A"
$PN"A16"19;
"PT38D"
$PN"D15"126;
"PT38C"
$PN"C15"42;
"PT38B"
$PN"B15"28;
"PT38A"
$PN"A15"41;
"PT30D"
$PN"D14"36;
"PT30C"
$PN"C14"34;
"PT30B"
$PN"B14"33;
"PT30A"
$PN"A14"32;
"PT29D"
$PN"D13"31;
"PT29C"
$PN"C13"30;
"PT29B"
$PN"B13"125;
"PT29A"
$PN"A13"83;
"PT28D"
$PN"F13"37;
"PT28C"
$PN"E13"45;
"PT27B"
$PN"E12"81;
"PT27A"
$PN"D12"80;
"PT24D"
$PN"D11"76;
"PT24C"
$PN"E11"88;
"PT24B"
$PN"A11"75;
"PT24A"
$PN"B11"64;
"PT23D"
$PN"F11"74;
"PT23C"
$PN"G11"73;
"PT21D"
$PN"G9"52;
"PT21C"
$PN"F9"51;
"PT21B"
$PN"A9"50;
"PT21A"
$PN"B9"59;
"PT20D"
$PN"D9"49;
"PT20C"
$PN"C9"48;
"PT20B"
$PN"A8"56;
"PT20A"
$PN"B8"60;
"PT14D"
$PN"D7"69;
"PT14C"
$PN"C6"97;
"PT14B"
$PN"A7"135;
"PT14A"
$PN"B6"136;
"PT13D"
$PN"E7"65;
"PT13C"
$PN"D6"55;
"PT13B"
$PN"A6"47;
"PT13A"
$PN"B5"71;
"PT12D"
$PN"C5"134;
"PT12C"
$PN"D5"133;
"PT12B"
$PN"A5"130;
"PT12A"
$PN"B4"131;
"PT10D"
$PN"C4"109;
"PT10C"
$PN"C3"101;
"PT10B"
$PN"A3"105;
"PT10A"
$PN"B2"104;
"PT11D"
$PN"G8"103;
"PT11C"
$PN"F8"132;
"PT22B"
$PN"E10"54;
"PT22A"
$PN"F10"53;
"PT11B"
$PN"A4"102;
"PT11A"
$PN"B3"106;
"PT15A"
$PN"C8"70;
"PT9A||L_GPLLT"
$PN"B1"98;
"PT9C"
$PN"E6"99;
"PT9B||L_GPLLC"
$PN"A2"86;
"PT9D"
$PN"F7"100;
"PT15B"
$PN"D8"61;
"PT23A||PCLKT0_1"
$PN"B10"77;
"PT23B||PCLKC0_1"
$PN"A10"72;
"PT44A||R_GPLLT"
$PN"A21"44;
"PT44B||R_GPLLC"
$PN"B22"138;
"PT27C||SCL||PCLKT0_0"
$PN"B12"24;
"PT27D||SDA||PCLKC0_0"
$PN"A12"78;
"PT28A"
$PN"G12"79;
"PT28B"
$PN"F12"82;
"PT31A"
$PN"G14"35;
"PT31B"
$PN"F14"29;
"PT41A"
$PN"A18"15;
"PT41B"
$PN"B19"14;
"PT43A||R_GPLLT"
$PN"A20"5;
"PT43B||R_GPLLC"
$PN"B21"4;
END.
